# BASEBOARD_FAB2 (Tioga Pass) — schematic parts with pin connectivity, parts 2146–2256 of 4751; source: Cadence DE-HDL packaged netlist (pstxprt.dat, pstxnet.dat, pstchip.dat)

CONX8  SMC-CONN60A-22-GP  pkg CONN-G7  page 245
  1  \1\  UNSPEC  = GND
  2  \2\  UNSPEC  = NC
  3  \3\  UNSPEC  = P3E_CPU0_PE2_SS_C_TXN<8>
  4  \4\  UNSPEC  = GND
  5  \5\  UNSPEC  = P3E_CPU0_PE2_SS_C_TXP<8>
  6  \6\  UNSPEC  = P3E_CPU0_PE2_SS_RXN<8>
  7  \7\  UNSPEC  = GND
  8  \8\  UNSPEC  = P3E_CPU0_PE2_SS_RXP<8>
  9  \9\  UNSPEC  = P3E_CPU0_PE2_SS_C_TXN<9>
  10  \10\  UNSPEC  = GND
  11  \11\  UNSPEC  = P3E_CPU0_PE2_SS_C_TXP<9>
  12  \12\  UNSPEC  = P3E_CPU0_PE2_SS_RXN<9>
  13  \13\  UNSPEC  = GND
  14  \14\  UNSPEC  = P3E_CPU0_PE2_SS_RXP<9>
  15  \15\  UNSPEC  = P3E_CPU0_PE2_SS_C_TXN<10>
  16  \16\  UNSPEC  = GND
  17  \17\  UNSPEC  = P3E_CPU0_PE2_SS_C_TXP<10>
  18  \18\  UNSPEC  = P3E_CPU0_PE2_SS_RXN<10>
  19  \19\  UNSPEC  = GND
  20  \20\  UNSPEC  = P3E_CPU0_PE2_SS_RXP<10>
  21  \21\  UNSPEC  = P3E_CPU0_PE2_SS_C_TXP<11>
  22  \22\  UNSPEC  = GND
  23  \23\  UNSPEC  = P3E_CPU0_PE2_SS_C_TXN<11>
  24  \24\  UNSPEC  = P3E_CPU0_PE2_SS_RXN<11>
  25  \25\  UNSPEC  = GND
  26  \26\  UNSPEC  = P3E_CPU0_PE2_SS_RXP<11>
  27  \27\  UNSPEC  = P3E_CPU0_PE2_SS_C_TXN<12>
  28  \28\  UNSPEC  = GND
  29  \29\  UNSPEC  = P3E_CPU0_PE2_SS_C_TXP<12>
  30  \30\  UNSPEC  = P3E_CPU0_PE2_SS_RXN<12>
  31  \31\  UNSPEC  = GND
  32  \32\  UNSPEC  = P3E_CPU0_PE2_SS_RXP<12>
  33  \33\  UNSPEC  = P3E_CPU0_PE2_SS_C_TXN<13>
  34  \34\  UNSPEC  = GND
  35  \35\  UNSPEC  = P3E_CPU0_PE2_SS_C_TXP<13>
  36  \36\  UNSPEC  = P3E_CPU0_PE2_SS_RXP<13>
  37  \37\  UNSPEC  = GND
  38  \38\  UNSPEC  = P3E_CPU0_PE2_SS_RXN<13>
  39  \39\  UNSPEC  = P3E_CPU0_PE2_SS_C_TXP<14>
  40  \40\  UNSPEC  = GND
  41  \41\  UNSPEC  = P3E_CPU0_PE2_SS_C_TXN<14>
  42  \42\  UNSPEC  = P3E_CPU0_PE2_SS_RXN<14>
  43  \43\  UNSPEC  = GND
  44  \44\  UNSPEC  = P3E_CPU0_PE2_SS_RXP<14>
  45  \45\  UNSPEC  = P3E_CPU0_PE2_SS_C_TXN<15>
  46  \46\  UNSPEC  = GND
  47  \47\  UNSPEC  = P3E_CPU0_PE2_SS_C_TXP<15>
  48  \48\  UNSPEC  = P3E_CPU0_PE2_SS_RXN<15>
  49  \49\  UNSPEC  = GND
  50  \50\  UNSPEC  = P3E_CPU0_PE2_SS_RXP<15>
  51  \51\  UNSPEC  = JTAG_RISER_TDI
  52  \52\  UNSPEC  = GND
  53  \53\  UNSPEC  = JTAG_RISER_TDO
  54  \54\  UNSPEC  = JTAG_RISER_TMS
  55  \55\  UNSPEC  = GND
  56  \56\  UNSPEC  = JTAG_RISER_TCK
  57  \57\  UNSPEC  = USB2_P02_DN
  58  \58\  UNSPEC  = GND
  59  \59\  UNSPEC  = USB2_P02_DP
  60  \60\  UNSPEC  = JTAG_RISER_TRST
  NP1  NP1  UNSPEC  = NC
  NP2  NP2  UNSPEC  = NC
  PTH1  PTH1  UNSPEC  = GND
  PTH2  PTH2  UNSPEC  = GND

CR1B1  DIODE  SDMK0340L EMPTY  pkg SM  page 161 : 1 = P5V_STBY ; 2 = FAN_PWM_OUT_SYS1_R
CR1B2  DIODE  SDMK0340L IC  pkg SM  page 161 : 1 = FAN_TACH2_CPU1_D1 ; 2 = FAN_TACH2_CPU1_D2
CR1E1  DIODE  SDMK0340L EMPTY  pkg SM  page 161 : 1 = P5V_STBY ; 2 = FAN_PWM_OUT_SYS0_R
CR1F1  DIODE  SDMK0340L IC  pkg SM  page 161 : 1 = FAN_TACH0_CPU0_D1 ; 2 = FAN_TACH0_CPU0_D2
CR1F3  DIODE  SDMK0340L IC  pkg SM  page 181 : 1 = FM_MATED_IN_D2_N ; 2 = FM_MATED_IN_D1_N
CR1F4  DIODE  SDMK0340L IC  pkg SM  page 181 : 1 = FM_MATED_IN_D1_N ; 2 = FM_MATED_IN_N
CR1F5  DIODE  MBRS340T3G EMPTY  pkg SM  page 200 : 1 = P12V_STBY ; 2 = GND
CR1L1  DIODE  1N4148W IC  pkg SM  page 168 : 1 = FM_DB_UART_SEL1_N ; 2 = FM_DB_UART_SEL0_N
CR1L2  DIODE  1N4148W IC  pkg SM  page 168 : 1 = FM_DB_UART_SEL2_N ; 2 = FM_DB_UART_SEL1_N
CR1L3  DIODE  1N4148W IC  pkg SM  page 168 : 1 = FM_DB_UART_SEL3_N ; 2 = FM_DB_UART_SEL2_N
CR1L4  DIODE  1N4148W IC  pkg SM  page 168 : 1 = FM_DB_UART_SEL4_N ; 2 = FM_DB_UART_SEL3_N

CR1M2  DIODEAC_DUAL_ARRAY  ESD3V3U4ULC IC  pkg SM9  page 176
  1  AC0  BI  = USB2_P01_ESD_DP
  2  AC1  BI  = USB2_P01_ESD_DN
  3  GND(0)  GROUND  = GND
  4  AC2  BI  = TP_USB_ESD_AC2
  5  AC3  BI  = TP_USB_ESD_AC3
  6  OUT3  OUT  = TP_USB_ESD_OUT3
  7  OUT2  OUT  = TP_USB_ESD_OUT2
  8  OUT1  OUT  = USB2_P01_ESD_DN
  9  OUT0  OUT  = USB2_P01_ESD_DP

CR2U1  DIODE2A_DUAL  BAS70-05 DIO  pkg SMLF  page 196
  1  A1  UNSPEC  = P3V3_STBY
  2  A2  UNSPEC  = A_P3V_BAT_R
  3  C  UNSPEC  = P3V3_RTC_STBY

CR3U1  DIODE  1N5819HW IC  pkg SMLF  page 189 : 1 = P3V3_STBY_PLD_D ; 2 = P3V3_STBY
CR3W1  DIODE  BAT54WS IC  pkg SMLF  page 249 : 1 = BMC_SELF_HW_D_RST ; 2 = BMC_SELF_HW_RST
CR6W1  DIODE  BAT54WS IC  pkg SMLF  page 247 : 1 = FM_CPU_CATERR_LVT3_N ; 2 = FM_CPU_CATERR_MSMI_LVT3_N
CR6W2  DIODE  BAT54WS IC  pkg SMLF  page 247 : 1 = FM_CPU_MSMI_LVT3_N ; 2 = FM_CPU_CATERR_MSMI_LVT3_N
CR7E1  DIODE  BAT54WS IC  pkg SMLF  page 196 : 1 = PWRGD_P3V3_STBY ; 2 = PWRGD_DSW_PWROK
CR8E1  DIODE  BAT54WS IC  pkg SMLF  page 196 : 1 = PWRGD_P12V_HSC ; 2 = PWRGD_P12V_HSC_DLY
CR9P1  DIODE  BAT54WS IC  pkg SMLF  page 200 : 1 = IRQ_UV_DETECT_N ; 2 = FM_DISABLE_FAN_N
CR9P2  DIODE  BAT54WS IC  pkg SMLF  page 200 : 1 = FM_UV_ADR_TRIGGER_N ; 2 = FM_DISABLE_FAN_N
CR9W1  DIODE  BAT54WS IC  pkg SMLF  page 155 : 1 = SPA_5V_SIN_SW ; 2 = SPA_5V_SIN_SW_D
CR10W1  DIODE  SDMK0340L IC  pkg SM  page 251 : 1 = PUMP_TACH_D ; 2 = PUMP_TACH_R
CR10W2  DIODE  SDMK0340L EMPTY  pkg SM  page 251 : 1 = P5V_STBY ; 2 = PUMP_PWM_OUT_R
CR10W3  DIODE  SDMK0340L IC  pkg SM  page 251 : 1 = PUMP_TACH1_D ; 2 = PUMP_TACH1_R

CR25W1  DIODEAC_DUAL_ARRAY  ESD3V3U4ULC IC  pkg SM9  page 252
  1  AC0  BI  = V_IO_B_J
  2  AC1  BI  = V_IO_G_J
  3  GND(0)  GROUND  = GND
  4  AC2  BI  = V_IO_R_J
  5  AC3  BI  = NC
  6  OUT3  OUT  = NC
  7  OUT2  OUT  = V_IO_R_J
  8  OUT1  OUT  = V_IO_G_J
  9  OUT0  OUT  = V_IO_B_J

CR25W2  DIODEAC_DUAL_ARRAY  ESD3V3U4ULC IC  pkg SM9  page 252
  1  AC0  BI  = V_IBMC_5V_DDC_SDA_J
  2  AC1  BI  = V_IBMC_5V_DDC_SCL_J
  3  GND(0)  GROUND  = GND
  4  AC2  BI  = V_IO_VSYNC_J
  5  AC3  BI  = V_IO_HSYNC_J
  6  OUT3  OUT  = V_IO_HSYNC_J
  7  OUT2  OUT  = V_IO_VSYNC_J
  8  OUT1  OUT  = V_IBMC_5V_DDC_SCL_J
  9  OUT0  OUT  = V_IBMC_5V_DDC_SDA_J

CR30W1  DIODEAC_DUAL_ARRAY  ESD3V3U4ULC IC  pkg SM9  page 253
  1  AC0  BI  = USB3_P01_FB_TXN
  2  AC1  BI  = USB3_P01_FB_TXP
  3  GND(0)  GROUND  = GND
  4  AC2  BI  = USB3_P01_FB_RXN
  5  AC3  BI  = USB3_P01_FB_RXP
  6  OUT3  OUT  = USB3_P01_FB_RXP
  7  OUT2  OUT  = USB3_P01_FB_RXN
  8  OUT1  OUT  = USB3_P01_FB_TXP
  9  OUT0  OUT  = USB3_P01_FB_TXN

CT1  CAP_A  0.1UF 16V 10% X7R  pkg 0402V  page 202 : 1 = VR_PVCCIN_CPU0_AIREF1 ; 2 = GND
CT2  CAP  1000PF 50V 10% X7R  pkg 0402LF  page 202 : 1 = A_TSENSE_PVCCIN_CPU0 ; 2 = GND
CT3  CAP  1000PF 50V 10% X7R  pkg 0402LF  page 202 : 1 = VR_PVCCIN_CPU0_PHASE1 ; 2 = VR_PVCCIN_CPU0_PHASE1_RC
CT4  CAP  1000PF 50V 10% X7R  pkg 0402LF  page 202 : 1 = A_TSENSE_PVCCIN_CPU0 ; 2 = GND
CT5  CAP  1000PF 50V 10% X7R  pkg 0402LF  page 202 : 1 = VR_PVCCIN_CPU0_PHASE2 ; 2 = VR_PVCCIN_CPU0_PHASE2_RC
CT6  CAP_A  0.1UF 16V 10% X7R  pkg 0402V  page 202 : 1 = VR_PVCCIN_CPU0_AIREF2 ; 2 = GND
CT7  CAP_A  0.1UF 16V 10% X7R  pkg 0402V  page 227 : 1 = VR_PVDDQ_KLM_AIREF1 ; 2 = GND
CT8  CAP  1000PF 50V 10% X7R  pkg 0402LF  page 227 : 1 = A_TSENSE_PVDDQ_KLM ; 2 = GND
CT9  CAP  1000PF 50V 10% X7R  pkg 0402LF  page 227 : 1 = VR_PVDDQ_KLM_PH1_SW ; 2 = VR_PVDDQ_KLM_PH1_RC
CT10  CAP  1000PF 50V 10% X7R  pkg 0402LF  page 227 : 1 = A_TSENSE_PVDDQ_KLM ; 2 = GND
CT11  CAP  1000PF 50V 10% X7R  pkg 0402LF  page 227 : 1 = VR_PVDDQ_KLM_PH2_SW ; 2 = VR_PVDDQ_KLM_PH2_RC
CT12  CAP_A  0.1UF 16V 10% X7R  pkg 0402V  page 227 : 1 = VR_PVDDQ_KLM_AIREF2 ; 2 = GND
CT13  CAP_A  0.1UF 16V 10% X7R  pkg 0402V  page 209 : 1 = VR_PVCCIN_CPU1_AIREF5 ; 2 = GND
CT14  CAP  1000PF 50V 10% X7R  pkg 0402LF  page 209 : 1 = VR_PVCCIN_CPU1_PHASE5 ; 2 = VR_PVCCIN_CPU1_PHASE5_RC
CT15  CAP  1000PF 50V 10% X7R  pkg 0402LF  page 209 : 1 = A_TSENSE_PVCCIN_CPU1 ; 2 = GND
CT16  CAP_A  0.1UF 16V 10% X7R  pkg 0402V  page 208 : 1 = VR_PVCCIN_CPU1_AIREF3 ; 2 = GND
CT18  CAP  1000PF 50V 10% X7R  pkg 0402LF  page 208 : 1 = VR_PVCCIN_CPU1_PHASE3 ; 2 = VR_PVCCIN_CPU1_PHASE3_RC
CT19  CAP  1000PF 50V 10% X7R  pkg 0402LF  page 208 : 1 = A_TSENSE_PVCCIN_CPU1 ; 2 = GND
CT20  CAP  1000PF 50V 10% X7R  pkg 0402LF  page 208 : 1 = VR_PVCCIN_CPU1_PHASE4 ; 2 = VR_PVCCIN_CPU1_PHASE4_RC
CT21  CAP_A  0.1UF 16V 10% X7R  pkg 0402V  page 208 : 1 = VR_PVCCIN_CPU1_AIREF4 ; 2 = GND
CT22  CAP  1000PF 50V 10% X7R  pkg 0402LF  page 207 : 1 = A_TSENSE_PVCCIN_CPU1 ; 2 = GND
CT23  CAP  1000PF 50V 10% X7R  pkg 0402LF  page 207 : 1 = VR_PVCCIN_CPU1_PHASE1 ; 2 = VR_PVCCIN_CPU1_PHASE1_RC
CT24  CAP_A  0.1UF 16V 10% X7R  pkg 0402V  page 207 : 1 = VR_PVCCIN_CPU1_AIREF1 ; 2 = GND
CT25  CAP_A  0.1UF 16V 10% X7R  pkg 0402V  page 207 : 1 = VR_PVCCIN_CPU1_AIREF2 ; 2 = GND
CT26  CAP  1000PF 50V 10% X7R  pkg 0402LF  page 207 : 1 = A_TSENSE_PVCCIN_CPU1 ; 2 = GND
CT27  CAP  1000PF 50V 10% X7R  pkg 0402LF  page 207 : 1 = VR_PVCCIN_CPU1_PHASE2 ; 2 = VR_PVCCIN_CPU1_PHASE2_RC
CT28  CAP  1000PF 50V 10% X7R  pkg 0402LF  page 224 : 1 = A_TSENSE_PVDDQ_GHJ ; 2 = GND
CT29  CAP  1000PF 50V 10% X7R  pkg 0402LF  page 224 : 1 = VR_PVDDQ_GHJ_PH1_SW ; 2 = VR_PVDDQ_GHJ_PH1_SW_RC
CT30  CAP_A  0.1UF 16V 10% X7R  pkg 0402V  page 224 : 1 = VR_PVDDQ_GHJ_AIREF1 ; 2 = GND
CT31  CAP_A  0.1UF 16V 10% X7R  pkg 0402V  page 224 : 1 = VR_PVDDQ_GHJ_AIREF2 ; 2 = GND
CT32  CAP  1000PF 50V 10% X7R  pkg 0402LF  page 224 : 1 = A_TSENSE_PVDDQ_GHJ ; 2 = GND
CT33  CAP  1000PF 50V 10% X7R  pkg 0402LF  page 224 : 1 = VR_PVDDQ_GHJ_PH2_SW ; 2 = VR_PVDDQ_GHJ_PH2_SW_RC
CT34  CAP  1000PF 50V 10% X7R  pkg 0402LF  page 204 : 1 = A_TSENSE_PVCCIN_CPU0 ; 2 = GND
CT35  CAP  1000PF 50V 10% X7R  pkg 0402LF  page 204 : 1 = VR_PVCCIN_CPU0_PHASE5 ; 2 = VR_PVCCIN_CPU0_PHASE5_RC
CT36  CAP_A  0.1UF 16V 10% X7R  pkg 0402V  page 204 : 1 = VR_PVCCIN_CPU0_AIREF5 ; 2 = GND
CT37  CAP  1000PF 50V 10% X7R  pkg 0402LF  page 203 : 1 = A_TSENSE_PVCCIN_CPU0 ; 2 = GND
CT38  CAP  1000PF 50V 10% X7R  pkg 0402LF  page 203 : 1 = VR_PVCCIN_CPU0_PHASE3 ; 2 = VR_PVCCIN_CPU0_PHASE3_RC
CT39  CAP_A  0.1UF 16V 10% X7R  pkg 0402V  page 203 : 1 = VR_PVCCIN_CPU0_AIREF3 ; 2 = GND
CT40  CAP_A  0.1UF 16V 10% X7R  pkg 0402V  page 203 : 1 = VR_PVCCIN_CPU0_AIREF4 ; 2 = GND
CT41  CAP  1000PF 50V 10% X7R  pkg 0402LF  page 203 : 1 = VR_PVCCIN_CPU0_PHASE4 ; 2 = VR_PVCCIN_CPU0_PHASE4_RC
CT42  CAP  1000PF 50V 10% X7R  pkg 0402LF  page 203 : 1 = A_TSENSE_PVCCIN_CPU0 ; 2 = GND
CT43  CAP  1000PF 50V 10% X7R  pkg 0402LF  page 219 : 1 = A_TSENSE_PVDDQ_DEF ; 2 = GND
CT44  CAP  1000PF 50V 10% X7R  pkg 0402LF  page 219 : 1 = VR_PVDDQ_DEF_PH1_SW ; 2 = VR_PVDDQ_DEF_PH1_SW_RC
CT45  CAP_A  0.1UF 16V 10% X7R  pkg 0402V  page 219 : 1 = VR_PVDDQ_DEF_AIREF1 ; 2 = GND
CT46  CAP_A  0.1UF 16V 10% X7R  pkg 0402V  page 219 : 1 = VR_PVDDQ_DEF_AIREF2 ; 2 = GND
CT47  CAP  1000PF 50V 10% X7R  pkg 0402LF  page 219 : 1 = VR_PVDDQ_DEF_PH2_SW ; 2 = VR_PVDDQ_DEF_PH2_SW_RC
CT48  CAP  1000PF 50V 10% X7R  pkg 0402LF  page 219 : 1 = A_TSENSE_PVDDQ_DEF ; 2 = GND
CT49  CAP  1000PF 50V 10% X7R  pkg 0402LF  page 216 : 1 = A_TSENSE_PVDDQ_ABC ; 2 = GND
CT50  CAP  1000PF 50V 10% X7R  pkg 0402LF  page 216 : 1 = VR_PVDDQ_ABC_PH1_SW ; 2 = VR_PVDDQ_ABC_PH1_SW_RC
CT51  CAP_A  0.1UF 16V 10% X7R  pkg 0402V  page 216 : 1 = VR_PVDDQ_ABC_AIREF1 ; 2 = GND
CT52  CAP_A  0.1UF 16V 10% X7R  pkg 0402V  page 216 : 1 = VR_PVDDQ_ABC_AIREF2 ; 2 = GND
CT53  CAP  1000PF 50V 10% X7R  pkg 0402LF  page 216 : 1 = VR_PVDDQ_ABC_PH2_SW ; 2 = VR_PVDDQ_ABC_PH2_SW_RC
CT54  CAP  1000PF 50V 10% X7R  pkg 0402LF  page 216 : 1 = A_TSENSE_PVDDQ_ABC ; 2 = GND
CT55  CAP  1000PF 50V 10% X7R  pkg 0402LF  page 210 : 1 = A_TSENSE_PVSA_CPU1 ; 2 = GND
CT56  CAP  1000PF 50V 10% X7R  pkg 0402LF  page 210 : 1 = VR_PVSA_CPU1_PHASE_SW ; 2 = VR_PVSA_CPU1_PHASE_SW_RC
CT57  CAP_A  0.1UF 16V 10% X7R  pkg 0402V  page 210 : 1 = VR_PVSA_CPU1_BIREF1 ; 2 = GND
CT58  CAP  1000PF 50V 10% X7R  pkg 0402LF  page 205 : 1 = A_TSENSE_PVSA_CPU0 ; 2 = GND
CT59  CAP  1000PF 50V 10% X7R  pkg 0402LF  page 205 : 1 = VR_PVSA_CPU0_PHASE_SW ; 2 = VR_PVSA_CPU0_PHASE_SW_RC
CT60  CAP_A  0.1UF 16V 10% X7R  pkg 0402V  page 205 : 1 = VR_PVSA_CPU0_BIREF1 ; 2 = GND
CT61  CAP  1000PF 50V 10% X7R  pkg 0402LF  page 214 : 1 = A_TSENSE_PVCCIO_CPU1 ; 2 = GND
CT62  CAP  1000PF 50V 10% X7R  pkg 0402LF  page 214 : 1 = VR_PVCCIO_CPU1_PH1_SW ; 2 = VR_PVCCIO_CPU1_PH1_SW_RC
CT63  CAP_A  0.1UF 16V 10% X7R  pkg 0402V  page 214 : 1 = VR_PVCCIO_CPU1_AIREF1 ; 2 = GND
CT64  CAP  1000PF 50V 10% X7R  pkg 0402LF  page 236 : 1 = A_TSENSE_PVNN_PCH_TMON ; 2 = GND
CT65  CAP  1000PF 50V 10% X7R  pkg 0402LF  page 236 : 1 = VR_PVNN_PCH_PH1_PHASE_SW ; 2 = VR_PVNN_PCH_PH1_PHASE_SW_RC
CT66  CAP_A  0.1UF 16V 10% X7R  pkg 0402V  page 236 : 1 = VR_PVNN_PCH_AIREF1 ; 2 = GND
CT67  CAP_A  0.1UF 16V 10% X7R  pkg 0402V  page 236 : 1 = VR_P1V05_PCH_BIREF1 ; 2 = GND
CT68  CAP  1000PF 50V 10% X7R  pkg 0402LF  page 236 : 1 = VR_P1V05_PCH_STBY_PH1_PHASE_SW ; 2 = VR_P1V05_PCH_STBY_PH1_SW_RC
CT69  CAP  1000PF 50V 10% X7R  pkg 0402LF  page 236 : 1 = A_TSENSE_P1V05_PCH_STBY_TMON ; 2 = GND
CT70  CAP_A  0.1UF 16V 10% X7R  pkg 0402V  page 212 : 1 = VR_PVCCIO_CPU0_AIREF1 ; 2 = GND
CT71  CAP  1000PF 50V 10% X7R  pkg 0402LF  page 212 : 1 = A_TSENSE_PVCCIO_CPU0 ; 2 = GND
CT72  CAP  1000PF 50V 10% X7R  pkg 0402LF  page 212 : 1 = VR_PVCCIO_CPU0_PH1_SW ; 2 = VR_PVCCIO_CPU0_PH1_SW_RC
CTI7  CAP  1000PF 50V 10% X7R  pkg 0402LF  page 208 : 1 = A_TSENSE_PVCCIN_CPU1 ; 2 = GND
D25W8  RB551V30-GP  pkg DISCRET-G  page 252 : A = P5V ; K = P5V_VGA_D
DS9A1  LED  IC  pkg 1NC  page 175 : 1 = FP_ID_LED_P5V_STBY_N ; 2 = FP_ID_LED_XOR_R
DS9A2  LED  IC  pkg 1NCLF  page 177 : 1 = FP_LED_HDD_ACTIVITY_AND_N ; 2 = FP_LED_HDD_ACTIVITY_AND_R_N
DS9A3  LED  IC  pkg 1NCLF  page 175 : 1 = FM_SPEAKER_PCH_N ; 2 = FM_BEEP_LED_P
DS9A4  LED  IC  pkg A1LF  page 158 : 1 = FM_UARTSW_LSB_R_N ; 2 = FM_UARTSW_LSB_N
DS9A5  LED  IC  pkg A1LF  page 119 : 1 = FM_PWR_LED_A ; 2 = FM_PWR_LED_K
DS9A6  LED  IC  pkg A1LF  page 177 : 1 = LED_P5V_STBY ; 2 = GND
DS9A7  LED  IC  pkg A1LF  page 158 : 1 = FM_UARTSW_MSB_R_N ; 2 = FM_UARTSW_MSB_N
DS9E1  LED  IC  pkg A1LF  page 151 : 1 = FM_HEARTBEAT_LED_A ; 2 = FM_HEARTBEAT_LED_K
DS9F1  LED  IC  pkg A1  page 177 : 1 = FM_RED_LED_ANODE ; 2 = FM_RED_LED_CATHODE
